(kicad_pcb
	(version 20260206)
	(generator "pcbnew")
	(generator_version "10.0")
	(general
		(thickness 1.6)
		(legacy_teardrops no)
	)
	(paper "A4")
	(title_block
		(title "baseboard — 13948-1b.1110WZS1818.brd")
		(comment 1 "Honey Badger (Wiwynn) / footprints 809-816 of 2523")
	)
	(layers
		(0 "F.Cu" signal "TOP")
		(4 "In1.Cu" signal "L2GND")
		(6 "In2.Cu" signal "L3")
		(8 "In3.Cu" signal "L4VCC")
		(10 "In4.Cu" signal "L5VCC")
		(12 "In5.Cu" signal "L6")
		(14 "In6.Cu" signal "L7GND")
		(2 "B.Cu" signal "BOTTOM")
		(9 "F.Adhes" user "F.Adhesive")
		(11 "B.Adhes" user "B.Adhesive")
		(13 "F.Paste" user "Package Geometry/Pastemask Top")
		(15 "B.Paste" user "Package Geometry/Pastemask Bottom")
		(5 "F.SilkS" user "Ref Des/Silkscreen Top")
		(7 "B.SilkS" user "Ref Des/Silkscreen Bottom")
		(1 "F.Mask" user "Board Geometry/Soldermask Top")
		(3 "B.Mask" user "Board Geometry/Soldermask Bottom")
		(17 "Dwgs.User" user "User.Drawings")
		(19 "Cmts.User" user "User.Comments")
		(21 "Eco1.User" user "User.Eco1")
		(23 "Eco2.User" user "User.Eco2")
		(25 "Edge.Cuts" user "Board Geometry/Outline")
		(27 "Margin" user)
		(31 "F.CrtYd" user "Package Geometry/Place Bound Top")
		(29 "B.CrtYd" user "Package Geometry/Place Bound Bottom")
		(35 "F.Fab" user "Ref Des/Assembly Top")
		(33 "B.Fab" user "Ref Des/Assembly Bottom")
	)
	(footprint ""
		(layer "F.Cu")
		(at 58.928 -211.074)
		(property "Reference" "PR9004"
			(at 0 0 0)
			(layer "F.SilkS")
			(hide yes)
			(effects
				(font
					(size 1.27 1.27)
				)
			)
		)
		(property "Value" "0R2J-2-GP"
			(at 0.064008 -3.993896 0)
			(unlocked yes)
			(layer "F.Fab")
			(hide yes)
			(effects
				(font
					(size 1.016 1.016)
					(thickness 0.1524)
				)
			)
		)
		(property "Device Type" "R402H16"
			(at 0.064008 -5.517896 0)
			(unlocked yes)
			(layer "F.Fab")
			(hide yes)
			(effects
				(font
					(size 1.016 1.016)
					(thickness 0.1524)
				)
			)
		)
		(duplicate_pad_numbers_are_jumpers no)
		(fp_line
			(start -0.508 -0.9398)
			(end -0.508 0.9398)
			(stroke
				(width 0.1524)
				(type default)
			)
			(layer "F.SilkS")
		)
		(fp_line
			(start 0.508 -0.9398)
			(end -0.508 -0.9398)
			(stroke
				(width 0.1524)
				(type default)
			)
			(layer "F.SilkS")
		)
		(fp_rect
			(start -0.508 0.9398)
			(end 0.508 -0.9398)
			(stroke
				(width 0)
				(type default)
			)
			(fill no)
			(layer "F.CrtYd")
		)
		(fp_rect
			(start -0.508 0.9398)
			(end 0.508 -0.9398)
			(stroke
				(width 0)
				(type default)
			)
			(fill no)
			(layer "F.Fab")
		)
		(pad "1" smd custom
			(at 0 -0.4445)
			(size 0.1397 0.1397)
			(layers "F.Cu" "F.Mask" "F.Paste")
			(net "HSW_SCL_2")
			(options
				(clearance outline)
				(anchor circle)
			)
			(primitives
				(gr_poly
					(pts
						(arc
							(start -0.1778 -0.2794)
							(mid -0.249642 -0.249642)
							(end -0.2794 -0.1778)
						)
						(arc
							(start -0.2794 0.1778)
							(mid -0.249642 0.249642)
							(end -0.1778 0.2794)
						)
						(arc
							(start 0.1778 0.2794)
							(mid 0.249642 0.249642)
							(end 0.2794 0.1778)
						)
						(arc
							(start 0.2794 -0.1778)
							(mid 0.249642 -0.249642)
							(end 0.1778 -0.2794)
						)
					)
					(width 0)
					(fill yes)
				)
			)
		)
		(pad "2" smd custom
			(at 0 0.4445)
			(size 0.1397 0.1397)
			(layers "F.Cu" "F.Mask" "F.Paste")
			(net "BMC_I2C_A_SCL")
			(options
				(clearance outline)
				(anchor circle)
			)
			(primitives
				(gr_poly
					(pts
						(arc
							(start -0.1778 -0.2794)
							(mid -0.249642 -0.249642)
							(end -0.2794 -0.1778)
						)
						(arc
							(start -0.2794 0.1778)
							(mid -0.249642 0.249642)
							(end -0.1778 0.2794)
						)
						(arc
							(start 0.1778 0.2794)
							(mid 0.249642 0.249642)
							(end 0.2794 0.1778)
						)
						(arc
							(start 0.2794 -0.1778)
							(mid 0.249642 -0.249642)
							(end 0.1778 -0.2794)
						)
					)
					(width 0)
					(fill yes)
				)
			)
		)
	)
	(footprint ""
		(layer "F.Cu")
		(at 280.289 -200.914)
		(property "Reference" "L5"
			(at 0 0 0)
			(layer "F.SilkS")
			(hide yes)
			(effects
				(font
					(size 1.27 1.27)
				)
			)
		)
		(property "Value" "MMZ2012S601ATA1N-GP"
			(at 0 -4.2418 0)
			(unlocked yes)
			(layer "F.Fab")
			(hide yes)
			(effects
				(font
					(size 1.016 1.016)
					(thickness 0.1524)
				)
			)
		)
		(property "Device Type" "L805H42"
			(at 0 -5.7912 0)
			(unlocked yes)
			(layer "F.Fab")
			(hide yes)
			(effects
				(font
					(size 1.016 1.016)
					(thickness 0.1524)
				)
			)
		)
		(duplicate_pad_numbers_are_jumpers no)
		(fp_line
			(start -0.889 -1.7018)
			(end 0.889 -1.7018)
			(stroke
				(width 0.1524)
				(type default)
			)
			(layer "F.SilkS")
		)
		(fp_line
			(start -0.889 1.7018)
			(end -0.889 -1.7018)
			(stroke
				(width 0.1524)
				(type default)
			)
			(layer "F.SilkS")
		)
		(fp_line
			(start 0.889 -1.7018)
			(end 0.889 1.7018)
			(stroke
				(width 0.1524)
				(type default)
			)
			(layer "F.SilkS")
		)
		(fp_line
			(start 0.889 1.7018)
			(end -0.889 1.7018)
			(stroke
				(width 0.1524)
				(type default)
			)
			(layer "F.SilkS")
		)
		(fp_rect
			(start -0.9652 1.778)
			(end 0.9652 -1.778)
			(stroke
				(width 0)
				(type default)
			)
			(fill no)
			(layer "F.CrtYd")
		)
		(fp_rect
			(start -0.9652 1.778)
			(end 0.9652 -1.778)
			(stroke
				(width 0)
				(type default)
			)
			(fill no)
			(layer "F.Fab")
		)
		(pad "1" smd rect
			(at 0 -0.9652)
			(size 1.397 1.143)
			(layers "F.Cu" "F.Mask" "F.Paste")
			(net "P3V3_STBY")
		)
		(pad "2" smd rect
			(at 0 0.9652)
			(size 1.397 1.143)
			(layers "F.Cu" "F.Mask" "F.Paste")
			(net "MPLLAV33")
		)
	)
	(footprint ""
		(layer "F.Cu")
		(at 268.351 -222.123 90)
		(property "Reference" "PC94"
			(at 0 0 90)
			(layer "F.SilkS")
			(hide yes)
			(effects
				(font
					(size 1.27 1.27)
				)
			)
		)
		(property "Value" "SC10U6D3V5KX-1GP"
			(at -0.0762 -6.1214 90)
			(unlocked yes)
			(layer "F.Fab")
			(hide yes)
			(effects
				(font
					(size 1.016 1.016)
					(thickness 0.1524)
				)
			)
		)
		(property "Device Type" "C805H54"
			(at -0.0762 -8.1534 90)
			(unlocked yes)
			(layer "F.Fab")
			(hide yes)
			(effects
				(font
					(size 1.016 1.016)
					(thickness 0.1524)
				)
			)
		)
		(duplicate_pad_numbers_are_jumpers no)
		(fp_line
			(start 0.635 0)
			(end -0.635 0)
			(stroke
				(width 0.508)
				(type default)
			)
			(layer "F.SilkS")
		)
		(fp_rect
			(start -0.9652 1.778)
			(end 0.9652 -1.778)
			(stroke
				(width 0)
				(type default)
			)
			(fill no)
			(layer "F.CrtYd")
		)
		(fp_poly
			(pts
				(xy -0.9652 -1.778) (xy 0.9652 -1.778) (xy 0.9652 1.778) (xy -0.9652 1.778)
			)
			(stroke
				(width 0)
				(type default)
			)
			(fill no)
			(layer "F.Fab")
		)
		(pad "1" smd rect
			(at 0 -0.9652 90)
			(size 1.397 1.143)
			(layers "F.Cu" "F.Mask" "F.Paste")
			(net "TPS74801_1V26_STBY_OUT")
		)
		(pad "2" smd rect
			(at 0 0.9652 90)
			(size 1.397 1.143)
			(layers "F.Cu" "F.Mask" "F.Paste")
			(net "GND")
		)
	)
	(footprint ""
		(layer "F.Cu")
		(at 262.89 -44.958)
		(property "Reference" "PR51"
			(at 0 0 0)
			(layer "F.SilkS")
			(hide yes)
			(effects
				(font
					(size 1.27 1.27)
				)
			)
		)
		(property "Value" "73K2R2F-GP"
			(at 0.064008 -3.993896 0)
			(unlocked yes)
			(layer "F.Fab")
			(hide yes)
			(effects
				(font
					(size 1.016 1.016)
					(thickness 0.1524)
				)
			)
		)
		(property "Device Type" "R402H16"
			(at 0.064008 -5.517896 0)
			(unlocked yes)
			(layer "F.Fab")
			(hide yes)
			(effects
				(font
					(size 1.016 1.016)
					(thickness 0.1524)
				)
			)
		)
		(duplicate_pad_numbers_are_jumpers no)
		(fp_line
			(start -0.508 -0.9398)
			(end -0.508 0.9398)
			(stroke
				(width 0.1524)
				(type default)
			)
			(layer "F.SilkS")
		)
		(fp_line
			(start 0.508 -0.9398)
			(end -0.508 -0.9398)
			(stroke
				(width 0.1524)
				(type default)
			)
			(layer "F.SilkS")
		)
		(fp_rect
			(start -0.508 0.9398)
			(end 0.508 -0.9398)
			(stroke
				(width 0)
				(type default)
			)
			(fill no)
			(layer "F.CrtYd")
		)
		(fp_rect
			(start -0.508 0.9398)
			(end 0.508 -0.9398)
			(stroke
				(width 0)
				(type default)
			)
			(fill no)
			(layer "F.Fab")
		)
		(pad "1" smd custom
			(at 0 -0.4445)
			(size 0.1397 0.1397)
			(layers "F.Cu" "F.Mask" "F.Paste")
			(net "AGND_P1V8_STBY")
			(options
				(clearance outline)
				(anchor circle)
			)
			(primitives
				(gr_poly
					(pts
						(arc
							(start -0.1778 -0.2794)
							(mid -0.249642 -0.249642)
							(end -0.2794 -0.1778)
						)
						(arc
							(start -0.2794 0.1778)
							(mid -0.249642 0.249642)
							(end -0.1778 0.2794)
						)
						(arc
							(start 0.1778 0.2794)
							(mid 0.249642 0.249642)
							(end 0.2794 0.1778)
						)
						(arc
							(start 0.2794 -0.1778)
							(mid 0.249642 -0.249642)
							(end 0.1778 -0.2794)
						)
					)
					(width 0)
					(fill yes)
				)
			)
		)
		(pad "2" smd custom
			(at 0 0.4445)
			(size 0.1397 0.1397)
			(layers "F.Cu" "F.Mask" "F.Paste")
			(net "P1V8_STBY_TRIP")
			(options
				(clearance outline)
				(anchor circle)
			)
			(primitives
				(gr_poly
					(pts
						(arc
							(start -0.1778 -0.2794)
							(mid -0.249642 -0.249642)
							(end -0.2794 -0.1778)
						)
						(arc
							(start -0.2794 0.1778)
							(mid -0.249642 0.249642)
							(end -0.1778 0.2794)
						)
						(arc
							(start 0.1778 0.2794)
							(mid 0.249642 0.249642)
							(end 0.2794 0.1778)
						)
						(arc
							(start 0.2794 -0.1778)
							(mid 0.249642 -0.249642)
							(end 0.1778 -0.2794)
						)
					)
					(width 0)
					(fill yes)
				)
			)
		)
	)
	(footprint ""
		(layer "F.Cu")
		(at 179.451 -218.821)
		(property "Reference" "C41"
			(at 0 0 0)
			(layer "F.SilkS")
			(hide yes)
			(effects
				(font
					(size 1.27 1.27)
				)
			)
		)
		(property "Value" "SCD1U16V2KX-3GP"
			(at 1.1811 -2.7051 0)
			(unlocked yes)
			(layer "F.Fab")
			(hide yes)
			(effects
				(font
					(size 1.016 1.016)
					(thickness 0.1524)
				)
			)
		)
		(property "Device Type" "C402H22"
			(at 1.1811 -4.2291 0)
			(unlocked yes)
			(layer "F.Fab")
			(hide yes)
			(effects
				(font
					(size 1.016 1.016)
					(thickness 0.1524)
				)
			)
		)
		(duplicate_pad_numbers_are_jumpers no)
		(fp_rect
			(start -0.4318 0.9525)
			(end 0.4318 -0.9525)
			(stroke
				(width 0)
				(type default)
			)
			(fill no)
			(layer "F.CrtYd")
		)
		(fp_rect
			(start -0.4318 0.9525)
			(end 0.4318 -0.9525)
			(stroke
				(width 0)
				(type default)
			)
			(fill no)
			(layer "F.Fab")
		)
		(pad "1" smd custom
			(at 0 -0.4445)
			(size 0.1524 0.1524)
			(layers "F.Cu" "F.Mask" "F.Paste")
			(net "P3V3_STBY")
			(options
				(clearance outline)
				(anchor circle)
			)
			(primitives
				(gr_poly
					(pts
						(arc
							(start 0.3048 -0.2032)
							(mid 0.275042 -0.275042)
							(end 0.2032 -0.3048)
						)
						(arc
							(start -0.2032 -0.3048)
							(mid -0.275042 -0.275042)
							(end -0.3048 -0.2032)
						)
						(arc
							(start -0.3048 0.2032)
							(mid -0.275042 0.275042)
							(end -0.2032 0.3048)
						)
						(arc
							(start 0.2032 0.3048)
							(mid 0.275042 0.275042)
							(end 0.3048 0.2032)
						)
					)
					(width 0)
					(fill yes)
				)
			)
		)
		(pad "2" smd custom
			(at 0 0.4445)
			(size 0.1524 0.1524)
			(layers "F.Cu" "F.Mask" "F.Paste")
			(net "GND")
			(options
				(clearance outline)
				(anchor circle)
			)
			(primitives
				(gr_poly
					(pts
						(arc
							(start 0.3048 -0.2032)
							(mid 0.275042 -0.275042)
							(end 0.2032 -0.3048)
						)
						(arc
							(start -0.2032 -0.3048)
							(mid -0.275042 -0.275042)
							(end -0.3048 -0.2032)
						)
						(arc
							(start -0.3048 0.2032)
							(mid -0.275042 0.275042)
							(end -0.2032 0.3048)
						)
						(arc
							(start 0.2032 0.3048)
							(mid 0.275042 0.275042)
							(end 0.3048 0.2032)
						)
					)
					(width 0)
					(fill yes)
				)
			)
		)
	)
	(footprint ""
		(layer "F.Cu")
		(at 305.308 -180.086)
		(property "Reference" "TP90"
			(at 0 0 0)
			(layer "F.SilkS")
			(hide yes)
			(effects
				(font
					(size 1.27 1.27)
				)
			)
		)
		(property "Value" "TPAD28"
			(at 0.0127 -1.8034 0)
			(unlocked yes)
			(layer "F.Fab")
			(hide yes)
			(effects
				(font
					(size 1.016 1.016)
					(thickness 0.1524)
				)
			)
		)
		(property "Device Type" "TPAD28"
			(at 0.0127 -3.3274 0)
			(unlocked yes)
			(layer "F.Fab")
			(hide yes)
			(effects
				(font
					(size 1.016 1.016)
					(thickness 0.1524)
				)
			)
		)
		(duplicate_pad_numbers_are_jumpers no)
		(fp_poly
			(pts
				(arc
					(start 0.3556 0)
					(mid -0.3556 0)
					(end 0.3556 0)
				)
			)
			(stroke
				(width 0)
				(type default)
			)
			(fill no)
			(layer "F.CrtYd")
		)
		(fp_poly
			(pts
				(arc
					(start 0.6096 0)
					(mid -0.6096 0)
					(end 0.6096 0)
				)
			)
			(stroke
				(width 0)
				(type default)
			)
			(fill no)
			(layer "F.Fab")
		)
		(pad "1" smd circle
			(at 0 0)
			(size 0.7112 0.7112)
			(layers "F.Cu" "F.Mask" "F.Paste")
			(net "TP_BMC_GPIOL0")
		)
	)
	(footprint ""
		(layer "F.Cu")
		(at 91.32697 -112.014 180)
		(property "Reference" "SC1240"
			(at 0 0 180)
			(layer "F.SilkS")
			(hide yes)
			(effects
				(font
					(size 1.27 1.27)
				)
			)
		)
		(property "Value" "SCD1U6D3V1KX-GP"
			(at -2.8321 -1.7399 180)
			(unlocked yes)
			(layer "F.Fab")
			(hide yes)
			(effects
				(font
					(size 1.016 1.016)
					(thickness 0.1524)
				)
			)
		)
		(property "Device Type" "C0201H13"
			(at -2.8321 -3.2639 180)
			(unlocked yes)
			(layer "F.Fab")
			(hide yes)
			(effects
				(font
					(size 1.016 1.016)
					(thickness 0.1524)
				)
			)
		)
		(duplicate_pad_numbers_are_jumpers no)
		(fp_rect
			(start -0.2794 0.6477)
			(end 0.2794 -0.6477)
			(stroke
				(width 0)
				(type default)
			)
			(fill no)
			(layer "F.CrtYd")
		)
		(fp_rect
			(start -0.2794 0.6477)
			(end 0.2794 -0.6477)
			(stroke
				(width 0)
				(type default)
			)
			(fill no)
			(layer "F.Fab")
		)
		(pad "1" smd custom
			(at 0 -0.2794 180)
			(size 0.0762 0.0762)
			(layers "F.Cu" "F.Mask" "F.Paste")
			(net "P1V8_E")
			(options
				(clearance outline)
				(anchor circle)
			)
			(primitives
				(gr_poly
					(pts
						(arc
							(start 0.1524 -0.127)
							(mid 0.137521 -0.162921)
							(end 0.1016 -0.1778)
						)
						(arc
							(start -0.1016 -0.1778)
							(mid -0.137521 -0.162921)
							(end -0.1524 -0.127)
						)
						(arc
							(start -0.1524 0.127)
							(mid -0.137521 0.162921)
							(end -0.1016 0.1778)
						)
						(arc
							(start 0.1016 0.1778)
							(mid 0.137521 0.162921)
							(end 0.1524 0.127)
						)
					)
					(width 0)
					(fill yes)
				)
			)
		)
		(pad "2" smd custom
			(at 0 0.2794 180)
			(size 0.0762 0.0762)
			(layers "F.Cu" "F.Mask" "F.Paste")
			(net "GND")
			(options
				(clearance outline)
				(anchor circle)
			)
			(primitives
				(gr_poly
					(pts
						(arc
							(start 0.1524 -0.127)
							(mid 0.137521 -0.162921)
							(end 0.1016 -0.1778)
						)
						(arc
							(start -0.1016 -0.1778)
							(mid -0.137521 -0.162921)
							(end -0.1524 -0.127)
						)
						(arc
							(start -0.1524 0.127)
							(mid -0.137521 0.162921)
							(end -0.1016 0.1778)
						)
						(arc
							(start 0.1016 0.1778)
							(mid 0.137521 0.162921)
							(end 0.1524 0.127)
						)
					)
					(width 0)
					(fill yes)
				)
			)
		)
	)
	(footprint ""
		(layer "F.Cu")
		(at 14.047216 -191.06388)
		(property "Reference" "SR271"
			(at 0 0 0)
			(layer "F.SilkS")
			(hide yes)
			(effects
				(font
					(size 1.27 1.27)
				)
			)
		)
		(property "Value" "4K7R2F-GP"
			(at 0.064008 -3.993896 0)
			(unlocked yes)
			(layer "F.Fab")
			(hide yes)
			(effects
				(font
					(size 1.016 1.016)
					(thickness 0.1524)
				)
			)
		)
		(property "Device Type" "R402H16"
			(at 0.064008 -5.517896 0)
			(unlocked yes)
			(layer "F.Fab")
			(hide yes)
			(effects
				(font
					(size 1.016 1.016)
					(thickness 0.1524)
				)
			)
		)
		(duplicate_pad_numbers_are_jumpers no)
		(fp_line
			(start -0.508 -0.9398)
			(end -0.508 0.9398)
			(stroke
				(width 0.1524)
				(type default)
			)
			(layer "F.SilkS")
		)
		(fp_line
			(start 0.508 -0.9398)
			(end -0.508 -0.9398)
			(stroke
				(width 0.1524)
				(type default)
			)
			(layer "F.SilkS")
		)
		(fp_rect
			(start -0.508 0.9398)
			(end 0.508 -0.9398)
			(stroke
				(width 0)
				(type default)
			)
			(fill no)
			(layer "F.CrtYd")
		)
		(fp_rect
			(start -0.508 0.9398)
			(end 0.508 -0.9398)
			(stroke
				(width 0)
				(type default)
			)
			(fill no)
			(layer "F.Fab")
		)
		(pad "1" smd custom
			(at 0 -0.4445)
			(size 0.1397 0.1397)
			(layers "F.Cu" "F.Mask" "F.Paste")
			(net "P1V8_E")
			(options
				(clearance outline)
				(anchor circle)
			)
			(primitives
				(gr_poly
					(pts
						(arc
							(start -0.1778 -0.2794)
							(mid -0.249642 -0.249642)
							(end -0.2794 -0.1778)
						)
						(arc
							(start -0.2794 0.1778)
							(mid -0.249642 0.249642)
							(end -0.1778 0.2794)
						)
						(arc
							(start 0.1778 0.2794)
							(mid 0.249642 0.249642)
							(end 0.2794 0.1778)
						)
						(arc
							(start 0.2794 -0.1778)
							(mid 0.249642 -0.249642)
							(end 0.1778 -0.2794)
						)
					)
					(width 0)
					(fill yes)
				)
			)
		)
		(pad "2" smd custom
			(at 0 0.4445)
			(size 0.1397 0.1397)
			(layers "F.Cu" "F.Mask" "F.Paste")
			(net "HDD_PRE_IO_INT_N")
			(options
				(clearance outline)
				(anchor circle)
			)
			(primitives
				(gr_poly
					(pts
						(arc
							(start -0.1778 -0.2794)
							(mid -0.249642 -0.249642)
							(end -0.2794 -0.1778)
						)
						(arc
							(start -0.2794 0.1778)
							(mid -0.249642 0.249642)
							(end -0.1778 0.2794)
						)
						(arc
							(start 0.1778 0.2794)
							(mid 0.249642 0.249642)
							(end 0.2794 0.1778)
						)
						(arc
							(start 0.2794 -0.1778)
							(mid 0.249642 -0.249642)
							(end 0.1778 -0.2794)
						)
					)
					(width 0)
					(fill yes)
				)
			)
		)
	)
)
